(kicad_pcb
	(version 20260206)
	(generator "pcbnew")
	(generator_version "10.0")
	(general
		(thickness 1.6)
		(legacy_teardrops no)
	)
	(paper "A4")
	(title_block
		(title "Bryce Canyon_SCC_16316-1_OCP.brd")
		(comment 1 "Bryce Canyon / footprints 1415-1423 of 1561")
	)
	(layers
		(0 "F.Cu" signal "TOP")
		(4 "In1.Cu" signal "L2GND")
		(6 "In2.Cu" signal "L3")
		(8 "In3.Cu" signal "L4VCC")
		(10 "In4.Cu" signal "L5VCC")
		(12 "In5.Cu" signal "L6")
		(14 "In6.Cu" signal "L7GND")
		(2 "B.Cu" signal "BOTTOM")
		(9 "F.Adhes" user "F.Adhesive")
		(11 "B.Adhes" user "B.Adhesive")
		(13 "F.Paste" user "Package Geometry/Pastemask Top")
		(15 "B.Paste" user "Package Geometry/Pastemask Bottom")
		(5 "F.SilkS" user "Ref Des/Silkscreen Top")
		(7 "B.SilkS" user "Ref Des/Silkscreen Bottom")
		(1 "F.Mask" user "Board Geometry/Soldermask Top")
		(3 "B.Mask" user "Board Geometry/Soldermask Bottom")
		(17 "Dwgs.User" user "User.Drawings")
		(19 "Cmts.User" user "User.Comments")
		(21 "Eco1.User" user "User.Eco1")
		(23 "Eco2.User" user "User.Eco2")
		(25 "Edge.Cuts" user "Board Geometry/Outline")
		(27 "Margin" user)
		(31 "F.CrtYd" user "Package Geometry/Place Bound Top")
		(29 "B.CrtYd" user "Package Geometry/Place Bound Bottom")
		(35 "F.Fab" user "Ref Des/Assembly Top")
		(33 "B.Fab" user "Ref Des/Assembly Bottom")
	)
	(footprint ""
		(layer "B.Cu")
		(at 188.6458 -33.1724 90)
		(property "Reference" "TP84"
			(at 0 0 90)
			(layer "B.SilkS")
			(hide yes)
			(effects
				(font
					(size 1.27 1.27)
				)
				(justify mirror)
			)
		)
		(property "Value" "TPAD28-2-GP"
			(at 0.0127 -1.6637 90)
			(unlocked yes)
			(layer "B.Fab")
			(hide yes)
			(effects
				(font
					(size 1.016 1.016)
					(thickness 0.1524)
				)
				(justify mirror)
			)
		)
		(property "Device Type" "TPAD28"
			(at 0.0127 -3.1877 90)
			(unlocked yes)
			(layer "B.Fab")
			(hide yes)
			(effects
				(font
					(size 1.016 1.016)
					(thickness 0.1524)
				)
				(justify mirror)
			)
		)
		(duplicate_pad_numbers_are_jumpers no)
		(fp_poly
			(pts
				(arc
					(start 0 0.3556)
					(mid 0 -0.3556)
					(end 0 0.3556)
				)
			)
			(stroke
				(width 0)
				(type default)
			)
			(fill no)
			(layer "B.CrtYd")
		)
		(fp_poly
			(pts
				(arc
					(start 0 0.6096)
					(mid 0 -0.6096)
					(end 0 0.6096)
				)
			)
			(stroke
				(width 0)
				(type default)
			)
			(fill no)
			(layer "B.Fab")
		)
		(pad "1" smd circle
			(at 0 0 270)
			(size 0.7112 0.7112)
			(layers "B.Cu" "B.Mask" "B.Paste")
			(net "IOC_GPIO_28")
		)
	)
	(footprint ""
		(layer "B.Cu")
		(at 195.988178 -31.926022)
		(property "Reference" "C366"
			(at 0 0 0)
			(layer "B.SilkS")
			(hide yes)
			(effects
				(font
					(size 1.27 1.27)
				)
				(justify mirror)
			)
		)
		(property "Value" "SCD1U16V2KX-3GP"
			(at -1.1811 -2.7051 0)
			(unlocked yes)
			(layer "B.Fab")
			(hide yes)
			(effects
				(font
					(size 1.016 1.016)
					(thickness 0.1524)
				)
				(justify mirror)
			)
		)
		(property "Device Type" "C402H22"
			(at -1.1811 -4.2291 0)
			(unlocked yes)
			(layer "B.Fab")
			(hide yes)
			(effects
				(font
					(size 1.016 1.016)
					(thickness 0.1524)
				)
				(justify mirror)
			)
		)
		(duplicate_pad_numbers_are_jumpers no)
		(fp_rect
			(start 0.4318 0.9525)
			(end -0.4318 -0.9525)
			(stroke
				(width 0)
				(type default)
			)
			(fill no)
			(layer "B.CrtYd")
		)
		(fp_rect
			(start 0.4318 0.9525)
			(end -0.4318 -0.9525)
			(stroke
				(width 0)
				(type default)
			)
			(fill no)
			(layer "B.Fab")
		)
		(pad "1" smd custom
			(at 0 -0.4445 180)
			(size 0.1524 0.1524)
			(layers "B.Cu" "B.Mask" "B.Paste")
			(net "PLL_VDD")
			(options
				(clearance outline)
				(anchor circle)
			)
			(primitives
				(gr_poly
					(pts
						(arc
							(start 0.3048 0.2032)
							(mid 0.275042 0.275042)
							(end 0.2032 0.3048)
						)
						(arc
							(start -0.2032 0.3048)
							(mid -0.275042 0.275042)
							(end -0.3048 0.2032)
						)
						(arc
							(start -0.3048 -0.2032)
							(mid -0.275042 -0.275042)
							(end -0.2032 -0.3048)
						)
						(arc
							(start 0.2032 -0.3048)
							(mid 0.275042 -0.275042)
							(end 0.3048 -0.2032)
						)
					)
					(width 0)
					(fill yes)
				)
			)
		)
		(pad "2" smd custom
			(at 0 0.4445 180)
			(size 0.1524 0.1524)
			(layers "B.Cu" "B.Mask" "B.Paste")
			(net "GND")
			(options
				(clearance outline)
				(anchor circle)
			)
			(primitives
				(gr_poly
					(pts
						(arc
							(start 0.3048 0.2032)
							(mid 0.275042 0.275042)
							(end 0.2032 0.3048)
						)
						(arc
							(start -0.2032 0.3048)
							(mid -0.275042 0.275042)
							(end -0.3048 0.2032)
						)
						(arc
							(start -0.3048 -0.2032)
							(mid -0.275042 -0.275042)
							(end -0.2032 -0.3048)
						)
						(arc
							(start 0.2032 -0.3048)
							(mid 0.275042 -0.275042)
							(end 0.3048 -0.2032)
						)
					)
					(width 0)
					(fill yes)
				)
			)
		)
	)
	(footprint ""
		(layer "B.Cu")
		(at 128.524 -66.675 -90)
		(property "Reference" "C292"
			(at 0 0 90)
			(layer "B.SilkS")
			(hide yes)
			(effects
				(font
					(size 1.27 1.27)
				)
				(justify mirror)
			)
		)
		(property "Value" "SCD1U6D3V1KX-GP"
			(at 2.8321 -1.7399 270)
			(unlocked yes)
			(layer "B.Fab")
			(hide yes)
			(effects
				(font
					(size 1.016 1.016)
					(thickness 0.1524)
				)
				(justify mirror)
			)
		)
		(property "Device Type" "C0201H13"
			(at 2.8321 -3.2639 270)
			(unlocked yes)
			(layer "B.Fab")
			(hide yes)
			(effects
				(font
					(size 1.016 1.016)
					(thickness 0.1524)
				)
				(justify mirror)
			)
		)
		(duplicate_pad_numbers_are_jumpers no)
		(fp_rect
			(start 0.2794 0.6477)
			(end -0.2794 -0.6477)
			(stroke
				(width 0)
				(type default)
			)
			(fill no)
			(layer "B.CrtYd")
		)
		(fp_rect
			(start 0.2794 0.6477)
			(end -0.2794 -0.6477)
			(stroke
				(width 0)
				(type default)
			)
			(fill no)
			(layer "B.Fab")
		)
		(pad "1" smd custom
			(at 0 -0.2794 90)
			(size 0.0762 0.0762)
			(layers "B.Cu" "B.Mask" "B.Paste")
			(net "GB_VDDA")
			(options
				(clearance outline)
				(anchor circle)
			)
			(primitives
				(gr_poly
					(pts
						(arc
							(start 0.1524 0.127)
							(mid 0.137521 0.162921)
							(end 0.1016 0.1778)
						)
						(arc
							(start -0.1016 0.1778)
							(mid -0.137521 0.162921)
							(end -0.1524 0.127)
						)
						(arc
							(start -0.1524 -0.127)
							(mid -0.137521 -0.162921)
							(end -0.1016 -0.1778)
						)
						(arc
							(start 0.1016 -0.1778)
							(mid 0.137521 -0.162921)
							(end 0.1524 -0.127)
						)
					)
					(width 0)
					(fill yes)
				)
			)
		)
		(pad "2" smd custom
			(at 0 0.2794 90)
			(size 0.0762 0.0762)
			(layers "B.Cu" "B.Mask" "B.Paste")
			(net "GND")
			(options
				(clearance outline)
				(anchor circle)
			)
			(primitives
				(gr_poly
					(pts
						(arc
							(start 0.1524 0.127)
							(mid 0.137521 0.162921)
							(end 0.1016 0.1778)
						)
						(arc
							(start -0.1016 0.1778)
							(mid -0.137521 0.162921)
							(end -0.1524 0.127)
						)
						(arc
							(start -0.1524 -0.127)
							(mid -0.137521 -0.162921)
							(end -0.1016 -0.1778)
						)
						(arc
							(start 0.1016 -0.1778)
							(mid 0.137521 -0.162921)
							(end 0.1524 -0.127)
						)
					)
					(width 0)
					(fill yes)
				)
			)
		)
	)
	(footprint ""
		(layer "B.Cu")
		(at 166.84625 -43.802808)
		(property "Reference" "C453"
			(at 0 0 0)
			(layer "B.SilkS")
			(hide yes)
			(effects
				(font
					(size 1.27 1.27)
				)
				(justify mirror)
			)
		)
		(property "Value" "SCD1U6D3V1KX-GP"
			(at 2.8321 -1.7399 0)
			(unlocked yes)
			(layer "B.Fab")
			(hide yes)
			(effects
				(font
					(size 1.016 1.016)
					(thickness 0.1524)
				)
				(justify mirror)
			)
		)
		(property "Device Type" "C0201H13"
			(at 2.8321 -3.2639 0)
			(unlocked yes)
			(layer "B.Fab")
			(hide yes)
			(effects
				(font
					(size 1.016 1.016)
					(thickness 0.1524)
				)
				(justify mirror)
			)
		)
		(duplicate_pad_numbers_are_jumpers no)
		(fp_rect
			(start 0.2794 0.6477)
			(end -0.2794 -0.6477)
			(stroke
				(width 0)
				(type default)
			)
			(fill no)
			(layer "B.CrtYd")
		)
		(fp_rect
			(start 0.2794 0.6477)
			(end -0.2794 -0.6477)
			(stroke
				(width 0)
				(type default)
			)
			(fill no)
			(layer "B.Fab")
		)
		(pad "1" smd custom
			(at 0 -0.2794 180)
			(size 0.0762 0.0762)
			(layers "B.Cu" "B.Mask" "B.Paste")
			(net "P1V8_C")
			(options
				(clearance outline)
				(anchor circle)
			)
			(primitives
				(gr_poly
					(pts
						(arc
							(start 0.1524 0.127)
							(mid 0.137521 0.162921)
							(end 0.1016 0.1778)
						)
						(arc
							(start -0.1016 0.1778)
							(mid -0.137521 0.162921)
							(end -0.1524 0.127)
						)
						(arc
							(start -0.1524 -0.127)
							(mid -0.137521 -0.162921)
							(end -0.1016 -0.1778)
						)
						(arc
							(start 0.1016 -0.1778)
							(mid 0.137521 -0.162921)
							(end 0.1524 -0.127)
						)
					)
					(width 0)
					(fill yes)
				)
			)
		)
		(pad "2" smd custom
			(at 0 0.2794 180)
			(size 0.0762 0.0762)
			(layers "B.Cu" "B.Mask" "B.Paste")
			(net "GND")
			(options
				(clearance outline)
				(anchor circle)
			)
			(primitives
				(gr_poly
					(pts
						(arc
							(start 0.1524 0.127)
							(mid 0.137521 0.162921)
							(end 0.1016 0.1778)
						)
						(arc
							(start -0.1016 0.1778)
							(mid -0.137521 0.162921)
							(end -0.1524 0.127)
						)
						(arc
							(start -0.1524 -0.127)
							(mid -0.137521 -0.162921)
							(end -0.1016 -0.1778)
						)
						(arc
							(start 0.1016 -0.1778)
							(mid 0.137521 -0.162921)
							(end 0.1524 -0.127)
						)
					)
					(width 0)
					(fill yes)
				)
			)
		)
	)
	(footprint ""
		(layer "B.Cu")
		(at 189.659514 -48.146208 -90)
		(property "Reference" "TP107"
			(at 0 0 90)
			(layer "B.SilkS")
			(hide yes)
			(effects
				(font
					(size 1.27 1.27)
				)
				(justify mirror)
			)
		)
		(property "Value" "TPAD28-2-GP"
			(at 0.0127 -1.6637 270)
			(unlocked yes)
			(layer "B.Fab")
			(hide yes)
			(effects
				(font
					(size 1.016 1.016)
					(thickness 0.1524)
				)
				(justify mirror)
			)
		)
		(property "Device Type" "TPAD28"
			(at 0.0127 -3.1877 270)
			(unlocked yes)
			(layer "B.Fab")
			(hide yes)
			(effects
				(font
					(size 1.016 1.016)
					(thickness 0.1524)
				)
				(justify mirror)
			)
		)
		(duplicate_pad_numbers_are_jumpers no)
		(fp_poly
			(pts
				(arc
					(start 0 -0.3556)
					(mid 0 0.3556)
					(end 0 -0.3556)
				)
			)
			(stroke
				(width 0)
				(type default)
			)
			(fill no)
			(layer "B.CrtYd")
		)
		(fp_poly
			(pts
				(arc
					(start 0 -0.6096)
					(mid 0 0.6096)
					(end 0 -0.6096)
				)
			)
			(stroke
				(width 0)
				(type default)
			)
			(fill no)
			(layer "B.Fab")
		)
		(pad "1" smd circle
			(at 0 0 90)
			(size 0.7112 0.7112)
			(layers "B.Cu" "B.Mask" "B.Paste")
			(net "XM_ADDR_20")
		)
	)
	(footprint ""
		(layer "B.Cu")
		(at 105.0036 -86.9442)
		(property "Reference" "R85"
			(at 0 0 0)
			(layer "B.SilkS")
			(hide yes)
			(effects
				(font
					(size 1.27 1.27)
				)
				(justify mirror)
			)
		)
		(property "Value" "4K75R2F-1-GP"
			(at -0.064008 -3.993896 0)
			(unlocked yes)
			(layer "B.Fab")
			(hide yes)
			(effects
				(font
					(size 1.016 1.016)
					(thickness 0.1524)
				)
				(justify mirror)
			)
		)
		(property "Device Type" "R402H16"
			(at -0.064008 -5.517896 0)
			(unlocked yes)
			(layer "B.Fab")
			(hide yes)
			(effects
				(font
					(size 1.016 1.016)
					(thickness 0.1524)
				)
				(justify mirror)
			)
		)
		(duplicate_pad_numbers_are_jumpers no)
		(fp_line
			(start -0.508 -0.9398)
			(end 0.508 -0.9398)
			(stroke
				(width 0.1524)
				(type default)
			)
			(layer "B.SilkS")
		)
		(fp_line
			(start 0.508 -0.9398)
			(end 0.508 0.9398)
			(stroke
				(width 0.1524)
				(type default)
			)
			(layer "B.SilkS")
		)
		(fp_rect
			(start 0.508 0.9398)
			(end -0.508 -0.9398)
			(stroke
				(width 0)
				(type default)
			)
			(fill no)
			(layer "B.CrtYd")
		)
		(fp_rect
			(start 0.508 0.9398)
			(end -0.508 -0.9398)
			(stroke
				(width 0)
				(type default)
			)
			(fill no)
			(layer "B.Fab")
		)
		(pad "1" smd custom
			(at 0 -0.4445 180)
			(size 0.1397 0.1397)
			(layers "B.Cu" "B.Mask" "B.Paste")
			(net "P1V8_E")
			(options
				(clearance outline)
				(anchor circle)
			)
			(primitives
				(gr_poly
					(pts
						(arc
							(start -0.1778 0.2794)
							(mid -0.249642 0.249642)
							(end -0.2794 0.1778)
						)
						(arc
							(start -0.2794 -0.1778)
							(mid -0.249642 -0.249642)
							(end -0.1778 -0.2794)
						)
						(arc
							(start 0.1778 -0.2794)
							(mid 0.249642 -0.249642)
							(end 0.2794 -0.1778)
						)
						(arc
							(start 0.2794 0.1778)
							(mid 0.249642 0.249642)
							(end 0.1778 0.2794)
						)
					)
					(width 0)
					(fill yes)
				)
			)
		)
		(pad "2" smd custom
			(at 0 0.4445 180)
			(size 0.1397 0.1397)
			(layers "B.Cu" "B.Mask" "B.Paste")
			(net "SXP_ACTIVE_0")
			(options
				(clearance outline)
				(anchor circle)
			)
			(primitives
				(gr_poly
					(pts
						(arc
							(start -0.1778 0.2794)
							(mid -0.249642 0.249642)
							(end -0.2794 0.1778)
						)
						(arc
							(start -0.2794 -0.1778)
							(mid -0.249642 -0.249642)
							(end -0.1778 -0.2794)
						)
						(arc
							(start 0.1778 -0.2794)
							(mid 0.249642 -0.249642)
							(end 0.2794 -0.1778)
						)
						(arc
							(start 0.2794 0.1778)
							(mid 0.249642 0.249642)
							(end 0.1778 0.2794)
						)
					)
					(width 0)
					(fill yes)
				)
			)
		)
	)
	(footprint ""
		(layer "B.Cu")
		(at 165.337744 -40.861996)
		(property "Reference" "TP97"
			(at 0 0 0)
			(layer "B.SilkS")
			(hide yes)
			(effects
				(font
					(size 1.27 1.27)
				)
				(justify mirror)
			)
		)
		(property "Value" "TPAD28-2-GP"
			(at 0.0127 -1.6637 0)
			(unlocked yes)
			(layer "B.Fab")
			(hide yes)
			(effects
				(font
					(size 1.016 1.016)
					(thickness 0.1524)
				)
				(justify mirror)
			)
		)
		(property "Device Type" "TPAD28"
			(at 0.0127 -3.1877 0)
			(unlocked yes)
			(layer "B.Fab")
			(hide yes)
			(effects
				(font
					(size 1.016 1.016)
					(thickness 0.1524)
				)
				(justify mirror)
			)
		)
		(duplicate_pad_numbers_are_jumpers no)
		(fp_poly
			(pts
				(arc
					(start 0.3556 0)
					(mid -0.3556 0)
					(end 0.3556 0)
				)
			)
			(stroke
				(width 0)
				(type default)
			)
			(fill no)
			(layer "B.CrtYd")
		)
		(fp_poly
			(pts
				(arc
					(start 0.6096 0)
					(mid -0.6096 0)
					(end 0.6096 0)
				)
			)
			(stroke
				(width 0)
				(type default)
			)
			(fill no)
			(layer "B.Fab")
		)
		(pad "1" smd circle
			(at 0 0 180)
			(size 0.7112 0.7112)
			(layers "B.Cu" "B.Mask" "B.Paste")
			(net "IOC_SIO_BLINK")
		)
	)
	(footprint ""
		(layer "B.Cu")
		(at 161.544 -52.07)
		(property "Reference" "R203"
			(at 0 0 0)
			(layer "B.SilkS")
			(hide yes)
			(effects
				(font
					(size 1.27 1.27)
				)
				(justify mirror)
			)
		)
		(property "Value" "2K2R2F-GP"
			(at -0.064008 -3.993896 0)
			(unlocked yes)
			(layer "B.Fab")
			(hide yes)
			(effects
				(font
					(size 1.016 1.016)
					(thickness 0.1524)
				)
				(justify mirror)
			)
		)
		(property "Device Type" "R402H16"
			(at -0.064008 -5.517896 0)
			(unlocked yes)
			(layer "B.Fab")
			(hide yes)
			(effects
				(font
					(size 1.016 1.016)
					(thickness 0.1524)
				)
				(justify mirror)
			)
		)
		(duplicate_pad_numbers_are_jumpers no)
		(fp_line
			(start -0.508 -0.9398)
			(end 0.508 -0.9398)
			(stroke
				(width 0.1524)
				(type default)
			)
			(layer "B.SilkS")
		)
		(fp_line
			(start 0.508 -0.9398)
			(end 0.508 0.9398)
			(stroke
				(width 0.1524)
				(type default)
			)
			(layer "B.SilkS")
		)
		(fp_rect
			(start 0.508 0.9398)
			(end -0.508 -0.9398)
			(stroke
				(width 0)
				(type default)
			)
			(fill no)
			(layer "B.CrtYd")
		)
		(fp_rect
			(start 0.508 0.9398)
			(end -0.508 -0.9398)
			(stroke
				(width 0)
				(type default)
			)
			(fill no)
			(layer "B.Fab")
		)
		(pad "1" smd custom
			(at 0 -0.4445 180)
			(size 0.1397 0.1397)
			(layers "B.Cu" "B.Mask" "B.Paste")
			(net "P1V8_C")
			(options
				(clearance outline)
				(anchor circle)
			)
			(primitives
				(gr_poly
					(pts
						(arc
							(start -0.1778 0.2794)
							(mid -0.249642 0.249642)
							(end -0.2794 0.1778)
						)
						(arc
							(start -0.2794 -0.1778)
							(mid -0.249642 -0.249642)
							(end -0.1778 -0.2794)
						)
						(arc
							(start 0.1778 -0.2794)
							(mid 0.249642 -0.249642)
							(end 0.2794 -0.1778)
						)
						(arc
							(start 0.2794 0.1778)
							(mid 0.249642 0.249642)
							(end 0.1778 0.2794)
						)
					)
					(width 0)
					(fill yes)
				)
			)
		)
		(pad "2" smd custom
			(at 0 0.4445 180)
			(size 0.1397 0.1397)
			(layers "B.Cu" "B.Mask" "B.Paste")
			(net "SIO_DOUT_1")
			(options
				(clearance outline)
				(anchor circle)
			)
			(primitives
				(gr_poly
					(pts
						(arc
							(start -0.1778 0.2794)
							(mid -0.249642 0.249642)
							(end -0.2794 0.1778)
						)
						(arc
							(start -0.2794 -0.1778)
							(mid -0.249642 -0.249642)
							(end -0.1778 -0.2794)
						)
						(arc
							(start 0.1778 -0.2794)
							(mid 0.249642 -0.249642)
							(end 0.2794 -0.1778)
						)
						(arc
							(start 0.2794 0.1778)
							(mid 0.249642 0.249642)
							(end 0.1778 0.2794)
						)
					)
					(width 0)
					(fill yes)
				)
			)
		)
	)
	(footprint ""
		(layer "B.Cu")
		(at 187.1472 -31.8008 90)
		(property "Reference" "TP82"
			(at 0 0 90)
			(layer "B.SilkS")
			(hide yes)
			(effects
				(font
					(size 1.27 1.27)
				)
				(justify mirror)
			)
		)
		(property "Value" "TPAD28-2-GP"
			(at 0.0127 -1.6637 90)
			(unlocked yes)
			(layer "B.Fab")
			(hide yes)
			(effects
				(font
					(size 1.016 1.016)
					(thickness 0.1524)
				)
				(justify mirror)
			)
		)
		(property "Device Type" "TPAD28"
			(at 0.0127 -3.1877 90)
			(unlocked yes)
			(layer "B.Fab")
			(hide yes)
			(effects
				(font
					(size 1.016 1.016)
					(thickness 0.1524)
				)
				(justify mirror)
			)
		)
		(duplicate_pad_numbers_are_jumpers no)
		(fp_poly
			(pts
				(arc
					(start 0 0.3556)
					(mid 0 -0.3556)
					(end 0 0.3556)
				)
			)
			(stroke
				(width 0)
				(type default)
			)
			(fill no)
			(layer "B.CrtYd")
		)
		(fp_poly
			(pts
				(arc
					(start 0 0.6096)
					(mid 0 -0.6096)
					(end 0 0.6096)
				)
			)
			(stroke
				(width 0)
				(type default)
			)
			(fill no)
			(layer "B.Fab")
		)
		(pad "1" smd circle
			(at 0 0 270)
			(size 0.7112 0.7112)
			(layers "B.Cu" "B.Mask" "B.Paste")
			(net "IOC_GPIO_27")
		)
	)
)
